# T6G (Grand Teton) — schematic netlist excerpt (pin names and nets, part order shuffled) for the footprints in the layout excerpt that follows; sources: Cadence DE-HDL packaged netlist, KiCad conversion of 04192023_DAF0TMB3IC0_F0TG_MB_C_brd_V02_OCP.brd

C2042  Q_CAP  100PF 50V 5% EMPTY  pkg 0402  page 257 : A = P3V3_AUX_ADC_MAM ; B = GND
R6504  Q_RES  10K 1% CHIP  pkg 0402LF  page 259 : A = P1V8_AUX ; B = PU_U38_6

(kicad_pcb
	(version 20260206)
	(generator "pcbnew")
	(generator_version "10.0")
	(general
		(thickness 1.6)
		(legacy_teardrops no)
	)
	(paper "A4")
	(title_block
		(title "04192023_DAF0TMB3IC0_F0TG_MB_C_brd_V02_OCP.brd")
		(comment 1 "Grand Teton / footprints 1330-1331 of 8354")
	)
	(layers
		(0 "F.Cu" signal "TOP")
		(4 "In1.Cu" signal "GND")
		(6 "In2.Cu" signal "IN1")
		(8 "In3.Cu" signal "GND1")
		(10 "In4.Cu" signal "IN2")
		(12 "In5.Cu" signal "GND2")
		(14 "In6.Cu" signal "IN3")
		(16 "In7.Cu" signal "GND3")
		(18 "In8.Cu" signal "VCC")
		(20 "In9.Cu" signal "VCC1")
		(22 "In10.Cu" signal "GND4")
		(24 "In11.Cu" signal "IN4")
		(26 "In12.Cu" signal "GND5")
		(28 "In13.Cu" signal "IN5")
		(30 "In14.Cu" signal "GND6")
		(32 "In15.Cu" signal "IN6")
		(34 "In16.Cu" signal "GND7")
		(2 "B.Cu" signal "BOTTOM")
		(9 "F.Adhes" user "F.Adhesive")
		(11 "B.Adhes" user "B.Adhesive")
		(13 "F.Paste" user "Package Geometry/Pastemask Top")
		(15 "B.Paste" user "Package Geometry/Pastemask Bottom")
		(5 "F.SilkS" user "Ref Des/Silkscreen Top")
		(7 "B.SilkS" user "Ref Des/Silkscreen Bottom")
		(1 "F.Mask" user "Board Geometry/Soldermask Top")
		(3 "B.Mask" user "Board Geometry/Soldermask Bottom")
		(17 "Dwgs.User" user "User.Drawings")
		(19 "Cmts.User" user "User.Comments")
		(21 "Eco1.User" user "User.Eco1")
		(23 "Eco2.User" user "User.Eco2")
		(25 "Edge.Cuts" user "Board Geometry/Outline")
		(27 "Margin" user)
		(31 "F.CrtYd" user "Package Geometry/Place Bound Top")
		(29 "B.CrtYd" user "Package Geometry/Place Bound Bottom")
		(35 "F.Fab" user "Ref Des/Assembly Top")
		(33 "B.Fab" user "Ref Des/Assembly Bottom")
	)
	(footprint ""
		(layer "F.Cu")
		(at 99.917504 -119.557038 90)
		(property "Reference" "R6504"
			(at 0 0 90)
			(layer "F.SilkS")
			(hide yes)
			(effects
				(font
					(size 1.27 1.27)
				)
			)
		)
		(property "Value" ""
			(at 0 0 90)
			(layer "F.Fab")
			(effects
				(font
					(size 1.27 1.27)
				)
			)
		)
		(duplicate_pad_numbers_are_jumpers no)
		(fp_line
			(start 0.7874 -0.4064)
			(end 0.7874 0.4064)
			(stroke
				(width 0.1524)
				(type default)
			)
			(layer "F.SilkS")
		)
		(fp_line
			(start -0.7874 -0.4064)
			(end 0.7874 -0.4064)
			(stroke
				(width 0.1524)
				(type default)
			)
			(layer "F.SilkS")
		)
		(fp_line
			(start 0.7874 0.4064)
			(end -0.7874 0.4064)
			(stroke
				(width 0.1524)
				(type default)
			)
			(layer "F.SilkS")
		)
		(fp_line
			(start -0.7874 0.4064)
			(end -0.7874 -0.4064)
			(stroke
				(width 0.1524)
				(type default)
			)
			(layer "F.SilkS")
		)
		(fp_line
			(start -0.12065 -0.305054)
			(end -0.12065 -0.2794)
			(stroke
				(width 0.1)
				(type default)
			)
			(layer "F.Fab")
		)
		(fp_line
			(start -0.67945 -0.305054)
			(end -0.12065 -0.305054)
			(stroke
				(width 0.1)
				(type default)
			)
			(layer "F.Fab")
		)
		(fp_line
			(start 0.67945 -0.3048)
			(end 0.67945 0.3048)
			(stroke
				(width 0.1)
				(type default)
			)
			(layer "F.Fab")
		)
		(fp_line
			(start 0.12065 -0.3048)
			(end 0.67945 -0.3048)
			(stroke
				(width 0.1)
				(type default)
			)
			(layer "F.Fab")
		)
		(fp_line
			(start 0.12065 -0.2794)
			(end 0.12065 -0.3048)
			(stroke
				(width 0.1)
				(type default)
			)
			(layer "F.Fab")
		)
		(fp_line
			(start -0.12065 -0.2794)
			(end 0.12065 -0.2794)
			(stroke
				(width 0.1)
				(type default)
			)
			(layer "F.Fab")
		)
		(fp_line
			(start 0.120396 0.2794)
			(end -0.12065 0.2794)
			(stroke
				(width 0.1)
				(type default)
			)
			(layer "F.Fab")
		)
		(fp_line
			(start -0.12065 0.2794)
			(end -0.12065 0.3048)
			(stroke
				(width 0.1)
				(type default)
			)
			(layer "F.Fab")
		)
		(fp_line
			(start 0.67945 0.3048)
			(end 0.120396 0.3048)
			(stroke
				(width 0.1)
				(type default)
			)
			(layer "F.Fab")
		)
		(fp_line
			(start 0.120396 0.3048)
			(end 0.120396 0.2794)
			(stroke
				(width 0.1)
				(type default)
			)
			(layer "F.Fab")
		)
		(fp_line
			(start -0.12065 0.3048)
			(end -0.67945 0.3048)
			(stroke
				(width 0.1)
				(type default)
			)
			(layer "F.Fab")
		)
		(fp_line
			(start -0.67945 0.3048)
			(end -0.67945 -0.305054)
			(stroke
				(width 0.1)
				(type default)
			)
			(layer "F.Fab")
		)
		(pad "1" smd circle
			(at -0.40005 0 90)
			(size 0 0)
			(layers "F.Cu" "F.Mask" "F.Paste")
			(net "P1V8_AUX")
		)
		(pad "2" smd circle
			(at 0.40005 0 90)
			(size 0 0)
			(layers "F.Cu" "F.Mask" "F.Paste")
			(net "PU_U38_6")
		)
	)
	(footprint ""
		(layer "F.Cu")
		(at 329.360022 -32.953706)
		(property "Reference" "C2042"
			(at 0 0 0)
			(layer "F.SilkS")
			(hide yes)
			(effects
				(font
					(size 1.27 1.27)
				)
			)
		)
		(property "Value" ""
			(at 0 0 0)
			(layer "F.Fab")
			(effects
				(font
					(size 1.27 1.27)
				)
			)
		)
		(duplicate_pad_numbers_are_jumpers no)
		(fp_line
			(start -0.7874 -0.4064)
			(end 0.7874 -0.4064)
			(stroke
				(width 0.1524)
				(type default)
			)
			(layer "F.SilkS")
		)
		(fp_line
			(start -0.7874 0.4064)
			(end -0.7874 -0.4064)
			(stroke
				(width 0.1524)
				(type default)
			)
			(layer "F.SilkS")
		)
		(fp_line
			(start 0.7874 -0.4064)
			(end 0.7874 0.4064)
			(stroke
				(width 0.1524)
				(type default)
			)
			(layer "F.SilkS")
		)
		(fp_line
			(start 0.7874 0.4064)
			(end -0.7874 0.4064)
			(stroke
				(width 0.1524)
				(type default)
			)
			(layer "F.SilkS")
		)
		(fp_line
			(start -0.67945 -0.305054)
			(end -0.12065 -0.305054)
			(stroke
				(width 0.1)
				(type default)
			)
			(layer "F.Fab")
		)
		(fp_line
			(start -0.67945 0.3048)
			(end -0.67945 -0.305054)
			(stroke
				(width 0.1)
				(type default)
			)
			(layer "F.Fab")
		)
		(fp_line
			(start -0.12065 -0.305054)
			(end -0.12065 -0.2794)
			(stroke
				(width 0.1)
				(type default)
			)
			(layer "F.Fab")
		)
		(fp_line
			(start -0.12065 -0.2794)
			(end 0.12065 -0.2794)
			(stroke
				(width 0.1)
				(type default)
			)
			(layer "F.Fab")
		)
		(fp_line
			(start -0.12065 0.2794)
			(end -0.12065 0.3048)
			(stroke
				(width 0.1)
				(type default)
			)
			(layer "F.Fab")
		)
		(fp_line
			(start -0.12065 0.3048)
			(end -0.67945 0.3048)
			(stroke
				(width 0.1)
				(type default)
			)
			(layer "F.Fab")
		)
		(fp_line
			(start 0.120396 0.2794)
			(end -0.12065 0.2794)
			(stroke
				(width 0.1)
				(type default)
			)
			(layer "F.Fab")
		)
		(fp_line
			(start 0.120396 0.3048)
			(end 0.120396 0.2794)
			(stroke
				(width 0.1)
				(type default)
			)
			(layer "F.Fab")
		)
		(fp_line
			(start 0.12065 -0.3048)
			(end 0.67945 -0.3048)
			(stroke
				(width 0.1)
				(type default)
			)
			(layer "F.Fab")
		)
		(fp_line
			(start 0.12065 -0.2794)
			(end 0.12065 -0.3048)
			(stroke
				(width 0.1)
				(type default)
			)
			(layer "F.Fab")
		)
		(fp_line
			(start 0.67945 -0.3048)
			(end 0.67945 0.3048)
			(stroke
				(width 0.1)
				(type default)
			)
			(layer "F.Fab")
		)
		(fp_line
			(start 0.67945 0.3048)
			(end 0.120396 0.3048)
			(stroke
				(width 0.1)
				(type default)
			)
			(layer "F.Fab")
		)
		(pad "1" smd circle
			(at -0.40005 0)
			(size 0 0)
			(layers "F.Cu" "F.Mask" "F.Paste")
			(net "P3V3_AUX_ADC_MAM")
		)
		(pad "2" smd circle
			(at 0.40005 0)
			(size 0 0)
			(layers "F.Cu" "F.Mask" "F.Paste")
			(net "GND")
		)
	)
)
